FILE_TYPE = MACRO_DRAWING;
SET COLOR_WIRE YELLOW;
SET COLOR_PROP ORANGE;
SET COLOR_DOT WHITE;
SET COLOR_ARC YELLOW;
SET COLOR_BODY GREEN;
SET COLOR_NOTE PURPLE;
SET PROP_DISPLAY VALUE;
SET PAGE_NUMBER P400;
FORCEADD PT5161LRS..4
(-5925 4450);
FORCEPROP 1 LAST LOCATION U6014
J 0
(-6375 5375);
DISPLAY 0.723404 (-6375 5375);
PAINT GREEN (-6375 5375);
FORCEPROP 0 LAST $SEC 4
J 0
(-6375 5525);
DISPLAY 0.680851 (-6375 5525);
PAINT MONO (-6375 5525);
DISPLAY INVISIBLE (-6375 5525);
FORCEPROP 0 LAST CDS_SEC 4
J 0
(-6375 5525);
DISPLAY 0.680851 (-6375 5525);
DISPLAY INVISIBLE (-6375 5525);
FORCEPROP 0 LASTPIN (-6525 5050) $PN BV20
J 2
(-6535 5060);
DISPLAY 0.680851 (-6535 5060);
PAINT MONO (-6535 5060);
FORCEPROP 0 LASTPIN (-6525 5000) $PN CE17
J 2
(-6535 5010);
DISPLAY 0.680851 (-6535 5010);
PAINT MONO (-6535 5010);
FORCEPROP 0 LASTPIN (-6525 4950) $PN CE20
J 2
(-6535 4960);
DISPLAY 0.680851 (-6535 4960);
PAINT MONO (-6535 4960);
FORCEPROP 0 LASTPIN (-6525 4900) $PN CM17
J 2
(-6535 4910);
DISPLAY 0.680851 (-6535 4910);
PAINT MONO (-6535 4910);
FORCEPROP 0 LASTPIN (-6525 4850) $PN CM20
J 2
(-6535 4860);
DISPLAY 0.680851 (-6535 4860);
PAINT MONO (-6535 4860);
FORCEPROP 0 LASTPIN (-6525 4400) $PN BV17
J 2
(-6535 4410);
DISPLAY 0.680851 (-6535 4410);
PAINT MONO (-6535 4410);
FORCEPROP 0 LASTPIN (-5375 5050) $PN AC17
J 0
(-5365 5060);
DISPLAY 0.680851 (-5365 5060);
PAINT MONO (-5365 5060);
FORCEPROP 0 LASTPIN (-5375 5000) $PN AC20
J 0
(-5365 5010);
DISPLAY 0.680851 (-5365 5010);
PAINT MONO (-5365 5010);
FORCEPROP 0 LASTPIN (-5375 4950) $PN AK17
J 0
(-5365 4960);
DISPLAY 0.680851 (-5365 4960);
PAINT MONO (-5365 4960);
FORCEPROP 0 LASTPIN (-5375 4900) $PN AK20
J 0
(-5365 4910);
DISPLAY 0.680851 (-5365 4910);
PAINT MONO (-5365 4910);
FORCEPROP 0 LASTPIN (-5375 4850) $PN AU17
J 0
(-5365 4860);
DISPLAY 0.680851 (-5365 4860);
PAINT MONO (-5365 4860);
FORCEPROP 0 LASTPIN (-5375 4800) $PN AU20
J 0
(-5365 4810);
DISPLAY 0.680851 (-5365 4810);
PAINT MONO (-5365 4810);
FORCEPROP 0 LASTPIN (-5375 4750) $PN BD17
J 0
(-5365 4760);
DISPLAY 0.680851 (-5365 4760);
PAINT MONO (-5365 4760);
FORCEPROP 0 LASTPIN (-5375 4700) $PN BD20
J 0
(-5365 4710);
DISPLAY 0.680851 (-5365 4710);
PAINT MONO (-5365 4710);
FORCEPROP 0 LASTPIN (-5375 4650) $PN DF17
J 0
(-5365 4660);
DISPLAY 0.680851 (-5365 4660);
PAINT MONO (-5365 4660);
FORCEPROP 0 LASTPIN (-5375 4600) $PN DF20
J 0
(-5365 4610);
DISPLAY 0.680851 (-5365 4610);
PAINT MONO (-5365 4610);
FORCEPROP 0 LASTPIN (-5375 4550) $PN DN17
J 0
(-5365 4560);
DISPLAY 0.680851 (-5365 4560);
PAINT MONO (-5365 4560);
FORCEPROP 0 LASTPIN (-5375 4500) $PN DN20
J 0
(-5365 4510);
DISPLAY 0.680851 (-5365 4510);
PAINT MONO (-5365 4510);
FORCEPROP 0 LASTPIN (-5375 4450) $PN DY17
J 0
(-5365 4460);
DISPLAY 0.680851 (-5365 4460);
PAINT MONO (-5365 4460);
FORCEPROP 0 LASTPIN (-5375 4400) $PN DY20
J 0
(-5365 4410);
DISPLAY 0.680851 (-5365 4410);
PAINT MONO (-5365 4410);
FORCEPROP 0 LASTPIN (-5375 4350) $PN EG17
J 0
(-5365 4360);
DISPLAY 0.680851 (-5365 4360);
PAINT MONO (-5365 4360);
FORCEPROP 0 LASTPIN (-5375 4300) $PN EG20
J 0
(-5365 4310);
DISPLAY 0.680851 (-5365 4310);
PAINT MONO (-5365 4310);
FORCEPROP 0 LASTPIN (-5375 4250) $PN EP17
J 0
(-5365 4260);
DISPLAY 0.680851 (-5365 4260);
PAINT MONO (-5365 4260);
FORCEPROP 0 LASTPIN (-5375 4200) $PN EP20
J 0
(-5365 4210);
DISPLAY 0.680851 (-5365 4210);
PAINT MONO (-5365 4210);
FORCEPROP 0 LASTPIN (-5375 4150) $PN T17
J 0
(-5365 4160);
DISPLAY 0.680851 (-5365 4160);
PAINT MONO (-5365 4160);
FORCEPROP 0 LASTPIN (-5375 4100) $PN T20
J 0
(-5365 4110);
DISPLAY 0.680851 (-5365 4110);
PAINT MONO (-5365 4110);
FORCEPROP 0 LASTPIN (-5375 3950) $PN BL17
J 0
(-5365 3960);
DISPLAY 0.680851 (-5365 3960);
PAINT MONO (-5365 3960);
FORCEPROP 0 LASTPIN (-5375 3900) $PN BL20
J 0
(-5365 3910);
DISPLAY 0.680851 (-5365 3910);
PAINT MONO (-5365 3910);
FORCEPROP 0 LASTPIN (-5375 3850) $PN CW17
J 0
(-5365 3860);
DISPLAY 0.680851 (-5365 3860);
PAINT MONO (-5365 3860);
FORCEPROP 0 LASTPIN (-5375 3800) $PN CW20
J 0
(-5365 3810);
DISPLAY 0.680851 (-5365 3810);
PAINT MONO (-5365 3810);
FORCEPROP 0 LASTPIN (-6525 3950) $PN G1
J 2
(-6535 3960);
DISPLAY 0.680851 (-6535 3960);
PAINT MONO (-6535 3960);
FORCEPROP 2 LAST PART_TYPE SMLF
J 0
(-6375 5475);
DISPLAY 0.680851 (-6375 5475);
FORCEPROP 2 LAST VALUE PT5161LRS
J 0
(-6375 5425);
DISPLAY 0.680851 (-6375 5425);
FORCEPROP 1 LAST MATERIAL IC
J 0
(-6375 5225);
DISPLAY 0.723404 (-6375 5225);
PAINT GREEN (-6375 5225);
FORCEPROP 1 LAST NEEDS_NO_SIZE TRUE
J 0
(-5925 4450);
DISPLAY 0.723404 (-5925 4450);
PAINT GREEN (-5925 4450);
DISPLAY INVISIBLE (-5925 4450);
FORCEPROP 1 LAST CDS_LMAN_SYM_OUTLINE -450,750,400,-750
J 0
(-5925 4450);
DISPLAY 0.468085 (-5925 4450);
PAINT GREEN (-5925 4450);
DISPLAY INVISIBLE (-5925 4450);
FORCEPROP 2 LAST CDS_LIB pure_quanta
J 0
(-5925 4450);
DISPLAY INVISIBLE (-5925 4450);
FORCEPROP 1 LAST PATH I1
J 0
(-5925 4450);
DISPLAY 0.723404 (-5925 4450);
PAINT GREEN (-5925 4450);
DISPLAY INVISIBLE (-5925 4450);
FORCEPROP 1 LAST PART_NUMBER AJ051610U03
J 0
(-6375 5300);
DISPLAY 0.723404 (-6375 5300);
PAINT GREEN (-6375 5300);
DISPLAY INVISIBLE (-6375 5300);
FORCEADD Q_RES..2
(-725 2100);
FORCEPROP 1 LAST LOCATION R711
J 0
(-680 2225);
DISPLAY 0.978723 (-680 2225);
FORCEPROP 0 LAST $SEC 1
J 0
(-675 2275);
DISPLAY 0.680851 (-675 2275);
PAINT MONO (-675 2275);
DISPLAY INVISIBLE (-675 2275);
FORCEPROP 0 LAST CDS_SEC 1
J 0
(-675 2275);
DISPLAY 0.680851 (-675 2275);
DISPLAY INVISIBLE (-675 2275);
FORCEPROP 1 LASTPIN (-725 2200) $PN 1
J 0
(-720 2162);
DISPLAY 0.787234 (-720 2162);
PAINT MONO (-720 2162);
FORCEPROP 1 LASTPIN (-725 2000) $PN 2
J 0
(-720 2010);
DISPLAY 0.787234 (-720 2010);
PAINT MONO (-720 2010);
FORCEPROP 1 LAST PACK_TYPE 0201LF
J 0
(-685 1925);
DISPLAY 0.978723 (-685 1925);
FORCEPROP 1 LAST VALUE 0
J 0
(-680 2175);
DISPLAY 0.978723 (-680 2175);
FORCEPROP 1 LAST TOLERANCE 5%
J 0
(-680 2125);
DISPLAY 0.978723 (-680 2125);
FORCEPROP 1 LAST MATERIAL CHIP
J 0
(-685 2025);
DISPLAY 0.978723 (-685 2025);
FORCEPROP 1 LAST WATTAGE 1/20W
J 0
(-685 2075);
DISPLAY 0.978723 (-685 2075);
FORCEPROP 2 LAST CDS_LIB pure_quanta
J 0
(-725 2100);
DISPLAY INVISIBLE (-725 2100);
FORCEPROP 1 LAST PATH I102
J 0
(-675 2275);
DISPLAY 0.978723 (-675 2275);
PAINT WHITE (-675 2275);
DISPLAY INVISIBLE (-675 2275);
FORCEPROP 1 LAST PART_NUMBER CS00001JE10
J 0
(-685 1975);
DISPLAY 0.978723 (-685 1975);
DISPLAY INVISIBLE (-685 1975);
FORCEADD Q_RES..2
(-875 1550);
FORCEPROP 1 LAST LOCATION R709
J 0
(-830 1675);
DISPLAY 0.978723 (-830 1675);
FORCEPROP 0 LAST $SEC 1
J 0
(-825 1725);
DISPLAY 0.680851 (-825 1725);
PAINT MONO (-825 1725);
DISPLAY INVISIBLE (-825 1725);
FORCEPROP 0 LAST CDS_SEC 1
J 0
(-825 1725);
DISPLAY 0.680851 (-825 1725);
DISPLAY INVISIBLE (-825 1725);
FORCEPROP 1 LASTPIN (-875 1650) $PN 1
J 0
(-870 1612);
DISPLAY 0.787234 (-870 1612);
PAINT MONO (-870 1612);
FORCEPROP 1 LASTPIN (-875 1450) $PN 2
J 0
(-870 1460);
DISPLAY 0.787234 (-870 1460);
PAINT MONO (-870 1460);
FORCEPROP 1 LAST PACK_TYPE 0201LF
J 0
(-835 1375);
DISPLAY 0.978723 (-835 1375);
FORCEPROP 1 LAST VALUE 0
J 0
(-830 1625);
DISPLAY 0.978723 (-830 1625);
FORCEPROP 1 LAST TOLERANCE 5%
J 0
(-830 1575);
DISPLAY 0.978723 (-830 1575);
FORCEPROP 1 LAST MATERIAL CHIP
J 0
(-835 1475);
DISPLAY 0.978723 (-835 1475);
FORCEPROP 1 LAST WATTAGE 1/20W
J 0
(-835 1525);
DISPLAY 0.978723 (-835 1525);
FORCEPROP 2 LAST CDS_LIB pure_quanta
J 0
(-875 1550);
DISPLAY INVISIBLE (-875 1550);
FORCEPROP 1 LAST PATH I103
J 0
(-825 1725);
DISPLAY 0.978723 (-825 1725);
PAINT WHITE (-825 1725);
DISPLAY INVISIBLE (-825 1725);
FORCEPROP 1 LAST PART_NUMBER CS00001JE10
J 0
(-835 1425);
DISPLAY 0.978723 (-835 1425);
DISPLAY INVISIBLE (-835 1425);
FORCEADD Q_RES..2
(-7075 3650);
FORCEPROP 1 LAST LOCATION R701
J 0
(-7030 3775);
DISPLAY 0.978723 (-7030 3775);
PAINT WHITE (-7030 3775);
FORCEPROP 0 LAST $SEC 1
J 0
(-7025 3825);
DISPLAY 0.680851 (-7025 3825);
PAINT MONO (-7025 3825);
DISPLAY INVISIBLE (-7025 3825);
FORCEPROP 0 LAST CDS_SEC 1
J 0
(-7025 3825);
DISPLAY 0.680851 (-7025 3825);
DISPLAY INVISIBLE (-7025 3825);
FORCEPROP 1 LASTPIN (-7075 3750) $PN 1
J 0
(-7070 3712);
DISPLAY 0.787234 (-7070 3712);
PAINT MONO (-7070 3712);
FORCEPROP 1 LASTPIN (-7075 3550) $PN 2
J 0
(-7070 3560);
DISPLAY 0.787234 (-7070 3560);
PAINT MONO (-7070 3560);
FORCEPROP 1 LAST WATTAGE 1/20W
J 0
(-7035 3625);
DISPLAY 0.978723 (-7035 3625);
FORCEPROP 1 LAST PACK_TYPE 0201LF
J 0
(-7035 3475);
DISPLAY 0.978723 (-7035 3475);
FORCEPROP 1 LAST MATERIAL CHIP
J 0
(-7035 3575);
DISPLAY 0.978723 (-7035 3575);
FORCEPROP 1 LAST TOLERANCE 1%
J 0
(-7030 3675);
DISPLAY 0.978723 (-7030 3675);
FORCEPROP 1 LAST VALUE 200
J 0
(-7030 3725);
DISPLAY 0.978723 (-7030 3725);
FORCEPROP 2 LAST CDS_LIB pure_quanta
J 0
(-7075 3650);
DISPLAY INVISIBLE (-7075 3650);
FORCEPROP 1 LAST PATH I105
J 0
(-7025 3825);
DISPLAY 0.978723 (-7025 3825);
PAINT WHITE (-7025 3825);
DISPLAY INVISIBLE (-7025 3825);
FORCEPROP 1 LAST PART_NUMBER CS12001FE12
J 0
(-7035 3525);
DISPLAY 0.978723 (-7035 3525);
DISPLAY INVISIBLE (-7035 3525);
FORCEADD Q_RES..2
(-8100 4200);
FORCEPROP 1 LAST LOCATION R699
J 0
(-8055 4325);
DISPLAY 0.787234 (-8055 4325);
PAINT SKYBLUE (-8055 4325);
FORCEPROP 0 LAST $SEC 1
J 0
(-8050 4375);
DISPLAY 0.680851 (-8050 4375);
PAINT MONO (-8050 4375);
DISPLAY INVISIBLE (-8050 4375);
FORCEPROP 0 LAST CDS_SEC 1
J 0
(-8050 4375);
DISPLAY 0.680851 (-8050 4375);
DISPLAY INVISIBLE (-8050 4375);
FORCEPROP 1 LASTPIN (-8100 4300) $PN 1
J 0
(-8095 4262);
DISPLAY 0.787234 (-8095 4262);
PAINT MONO (-8095 4262);
FORCEPROP 1 LASTPIN (-8100 4100) $PN 2
J 0
(-8095 4110);
DISPLAY 0.787234 (-8095 4110);
PAINT MONO (-8095 4110);
FORCEPROP 1 LAST PACK_TYPE 0201LF
J 0
(-8060 4025);
DISPLAY 0.787234 (-8060 4025);
FORCEPROP 1 LAST TOLERANCE 1%
J 0
(-8055 4225);
DISPLAY 0.787234 (-8055 4225);
FORCEPROP 1 LAST MATERIAL EMPTY
J 0
(-8060 4125);
DISPLAY 0.787234 (-8060 4125);
PAINT RED (-8060 4125);
FORCEPROP 1 LAST WATTAGE 1/20W
J 0
(-8060 4175);
DISPLAY 0.787234 (-8060 4175);
FORCEPROP 1 LAST VALUE 1K
J 0
(-8055 4275);
DISPLAY 0.787234 (-8055 4275);
FORCEPROP 2 LAST CDS_LIB pure_quanta
J 0
(-8100 4200);
DISPLAY INVISIBLE (-8100 4200);
FORCEPROP 1 LAST PATH I106
J 0
(-8050 4375);
DISPLAY 0.978723 (-8050 4375);
PAINT WHITE (-8050 4375);
DISPLAY INVISIBLE (-8050 4375);
FORCEPROP 1 LAST PART_NUMBER CS21001FE07
J 0
(-8060 4075);
DISPLAY 0.978723 (-8060 4075);
DISPLAY INVISIBLE (-8060 4075);
FORCEADD PT5161LRS..5
(-1850 3875);
FORCEPROP 1 LAST LOCATION U6014
J 0
(-2200 6200);
DISPLAY 0.723404 (-2200 6200);
PAINT GREEN (-2200 6200);
FORCEPROP 0 LAST $SEC 5
J 0
(-2200 6350);
DISPLAY 0.680851 (-2200 6350);
PAINT MONO (-2200 6350);
DISPLAY INVISIBLE (-2200 6350);
FORCEPROP 0 LAST CDS_SEC 5
J 0
(-2200 6350);
DISPLAY 0.680851 (-2200 6350);
DISPLAY INVISIBLE (-2200 6350);
FORCEPROP 0 LASTPIN (-2350 5875) $PN AC13
J 2
(-2360 5885);
DISPLAY 0.680851 (-2360 5885);
PAINT MONO (-2360 5885);
FORCEPROP 0 LASTPIN (-2350 5825) $PN AC22
J 2
(-2360 5835);
DISPLAY 0.680851 (-2360 5835);
PAINT MONO (-2360 5835);
FORCEPROP 0 LASTPIN (-2350 5775) $PN AC32
J 2
(-2360 5785);
DISPLAY 0.680851 (-2360 5785);
PAINT MONO (-2360 5785);
FORCEPROP 0 LASTPIN (-2350 5725) $PN AC4
J 2
(-2360 5735);
DISPLAY 0.680851 (-2360 5735);
PAINT MONO (-2360 5735);
FORCEPROP 0 LASTPIN (-2350 5675) $PN AD2
J 2
(-2360 5685);
DISPLAY 0.680851 (-2360 5685);
PAINT MONO (-2360 5685);
FORCEPROP 0 LASTPIN (-2350 5625) $PN AD34
J 2
(-2360 5635);
DISPLAY 0.680851 (-2360 5635);
PAINT MONO (-2360 5635);
FORCEPROP 0 LASTPIN (-2350 5575) $PN AE1
J 2
(-2360 5585);
DISPLAY 0.680851 (-2360 5585);
PAINT MONO (-2360 5585);
FORCEPROP 0 LASTPIN (-2350 5525) $PN AE35
J 2
(-2360 5535);
DISPLAY 0.680851 (-2360 5535);
PAINT MONO (-2360 5535);
FORCEPROP 0 LASTPIN (-2350 5475) $PN AK13
J 2
(-2360 5485);
DISPLAY 0.680851 (-2360 5485);
PAINT MONO (-2360 5485);
FORCEPROP 0 LASTPIN (-2350 5425) $PN AK22
J 2
(-2360 5435);
DISPLAY 0.680851 (-2360 5435);
PAINT MONO (-2360 5435);
FORCEPROP 0 LASTPIN (-2350 5375) $PN AK32
J 2
(-2360 5385);
DISPLAY 0.680851 (-2360 5385);
PAINT MONO (-2360 5385);
FORCEPROP 0 LASTPIN (-2350 5325) $PN AK4
J 2
(-2360 5335);
DISPLAY 0.680851 (-2360 5335);
PAINT MONO (-2360 5335);
FORCEPROP 0 LASTPIN (-2350 5275) $PN AL2
J 2
(-2360 5285);
DISPLAY 0.680851 (-2360 5285);
PAINT MONO (-2360 5285);
FORCEPROP 0 LASTPIN (-2350 5225) $PN AL34
J 2
(-2360 5235);
DISPLAY 0.680851 (-2360 5235);
PAINT MONO (-2360 5235);
FORCEPROP 0 LASTPIN (-2350 5175) $PN AM1
J 2
(-2360 5185);
DISPLAY 0.680851 (-2360 5185);
PAINT MONO (-2360 5185);
FORCEPROP 0 LASTPIN (-2350 5125) $PN AM35
J 2
(-2360 5135);
DISPLAY 0.680851 (-2360 5135);
PAINT MONO (-2360 5135);
FORCEPROP 0 LASTPIN (-2350 5075) $PN AU13
J 2
(-2360 5085);
DISPLAY 0.680851 (-2360 5085);
PAINT MONO (-2360 5085);
FORCEPROP 0 LASTPIN (-2350 5025) $PN AU22
J 2
(-2360 5035);
DISPLAY 0.680851 (-2360 5035);
PAINT MONO (-2360 5035);
FORCEPROP 0 LASTPIN (-2350 4975) $PN AU32
J 2
(-2360 4985);
DISPLAY 0.680851 (-2360 4985);
PAINT MONO (-2360 4985);
FORCEPROP 0 LASTPIN (-2350 4925) $PN AU4
J 2
(-2360 4935);
DISPLAY 0.680851 (-2360 4935);
PAINT MONO (-2360 4935);
FORCEPROP 0 LASTPIN (-2350 4875) $PN AV2
J 2
(-2360 4885);
DISPLAY 0.680851 (-2360 4885);
PAINT MONO (-2360 4885);
FORCEPROP 0 LASTPIN (-2350 4825) $PN AV34
J 2
(-2360 4835);
DISPLAY 0.680851 (-2360 4835);
PAINT MONO (-2360 4835);
FORCEPROP 0 LASTPIN (-2350 4775) $PN AW1
J 2
(-2360 4785);
DISPLAY 0.680851 (-2360 4785);
PAINT MONO (-2360 4785);
FORCEPROP 0 LASTPIN (-2350 4725) $PN AW35
J 2
(-2360 4735);
DISPLAY 0.680851 (-2360 4735);
PAINT MONO (-2360 4735);
FORCEPROP 0 LASTPIN (-2350 4675) $PN B19
J 2
(-2360 4685);
DISPLAY 0.680851 (-2360 4685);
PAINT MONO (-2360 4685);
FORCEPROP 0 LASTPIN (-2350 4625) $PN BD13
J 2
(-2360 4635);
DISPLAY 0.680851 (-2360 4635);
PAINT MONO (-2360 4635);
FORCEPROP 0 LASTPIN (-2350 4575) $PN BD22
J 2
(-2360 4585);
DISPLAY 0.680851 (-2360 4585);
PAINT MONO (-2360 4585);
FORCEPROP 0 LASTPIN (-2350 4525) $PN BD32
J 2
(-2360 4535);
DISPLAY 0.680851 (-2360 4535);
PAINT MONO (-2360 4535);
FORCEPROP 0 LASTPIN (-2350 4475) $PN BD4
J 2
(-2360 4485);
DISPLAY 0.680851 (-2360 4485);
PAINT MONO (-2360 4485);
FORCEPROP 0 LASTPIN (-2350 4425) $PN BE2
J 2
(-2360 4435);
DISPLAY 0.680851 (-2360 4435);
PAINT MONO (-2360 4435);
FORCEPROP 0 LASTPIN (-2350 4375) $PN BE34
J 2
(-2360 4385);
DISPLAY 0.680851 (-2360 4385);
PAINT MONO (-2360 4385);
FORCEPROP 0 LASTPIN (-2350 4325) $PN BF1
J 2
(-2360 4335);
DISPLAY 0.680851 (-2360 4335);
PAINT MONO (-2360 4335);
FORCEPROP 0 LASTPIN (-2350 4275) $PN BF35
J 2
(-2360 4285);
DISPLAY 0.680851 (-2360 4285);
PAINT MONO (-2360 4285);
FORCEPROP 0 LASTPIN (-2350 4225) $PN BL13
J 2
(-2360 4235);
DISPLAY 0.680851 (-2360 4235);
PAINT MONO (-2360 4235);
FORCEPROP 0 LASTPIN (-2350 4175) $PN BL22
J 2
(-2360 4185);
DISPLAY 0.680851 (-2360 4185);
PAINT MONO (-2360 4185);
FORCEPROP 0 LASTPIN (-2350 4125) $PN BL32
J 2
(-2360 4135);
DISPLAY 0.680851 (-2360 4135);
PAINT MONO (-2360 4135);
FORCEPROP 0 LASTPIN (-2350 4075) $PN BL4
J 2
(-2360 4085);
DISPLAY 0.680851 (-2360 4085);
PAINT MONO (-2360 4085);
FORCEPROP 0 LASTPIN (-2350 4025) $PN BM2
J 2
(-2360 4035);
DISPLAY 0.680851 (-2360 4035);
PAINT MONO (-2360 4035);
FORCEPROP 0 LASTPIN (-2350 3975) $PN BM34
J 2
(-2360 3985);
DISPLAY 0.680851 (-2360 3985);
PAINT MONO (-2360 3985);
FORCEPROP 0 LASTPIN (-2350 3925) $PN BN1
J 2
(-2360 3935);
DISPLAY 0.680851 (-2360 3935);
PAINT MONO (-2360 3935);
FORCEPROP 0 LASTPIN (-2350 3875) $PN BN35
J 2
(-2360 3885);
DISPLAY 0.680851 (-2360 3885);
PAINT MONO (-2360 3885);
FORCEPROP 0 LASTPIN (-2350 3825) $PN BV13
J 2
(-2360 3835);
DISPLAY 0.680851 (-2360 3835);
PAINT MONO (-2360 3835);
FORCEPROP 0 LASTPIN (-2350 3775) $PN BV22
J 2
(-2360 3785);
DISPLAY 0.680851 (-2360 3785);
PAINT MONO (-2360 3785);
FORCEPROP 0 LASTPIN (-2350 3725) $PN BV32
J 2
(-2360 3735);
DISPLAY 0.680851 (-2360 3735);
PAINT MONO (-2360 3735);
FORCEPROP 0 LASTPIN (-2350 3675) $PN BV4
J 2
(-2360 3685);
DISPLAY 0.680851 (-2360 3685);
PAINT MONO (-2360 3685);
FORCEPROP 0 LASTPIN (-2350 3625) $PN BW2
J 2
(-2360 3635);
DISPLAY 0.680851 (-2360 3635);
PAINT MONO (-2360 3635);
FORCEPROP 0 LASTPIN (-2350 3575) $PN BW34
J 2
(-2360 3585);
DISPLAY 0.680851 (-2360 3585);
PAINT MONO (-2360 3585);
FORCEPROP 0 LASTPIN (-2350 3525) $PN BY1
J 2
(-2360 3535);
DISPLAY 0.680851 (-2360 3535);
PAINT MONO (-2360 3535);
FORCEPROP 0 LASTPIN (-2350 3475) $PN BY35
J 2
(-2360 3485);
DISPLAY 0.680851 (-2360 3485);
PAINT MONO (-2360 3485);
FORCEPROP 0 LASTPIN (-2350 3425) $PN CE13
J 2
(-2360 3435);
DISPLAY 0.680851 (-2360 3435);
PAINT MONO (-2360 3435);
FORCEPROP 0 LASTPIN (-2350 3375) $PN CE22
J 2
(-2360 3385);
DISPLAY 0.680851 (-2360 3385);
PAINT MONO (-2360 3385);
FORCEPROP 0 LASTPIN (-2350 3325) $PN CE32
J 2
(-2360 3335);
DISPLAY 0.680851 (-2360 3335);
PAINT MONO (-2360 3335);
FORCEPROP 0 LASTPIN (-2350 3275) $PN CE4
J 2
(-2360 3285);
DISPLAY 0.680851 (-2360 3285);
PAINT MONO (-2360 3285);
FORCEPROP 0 LASTPIN (-2350 3225) $PN CF2
J 2
(-2360 3235);
DISPLAY 0.680851 (-2360 3235);
PAINT MONO (-2360 3235);
FORCEPROP 0 LASTPIN (-2350 3175) $PN CF34
J 2
(-2360 3185);
DISPLAY 0.680851 (-2360 3185);
PAINT MONO (-2360 3185);
FORCEPROP 0 LASTPIN (-2350 3125) $PN CG1
J 2
(-2360 3135);
DISPLAY 0.680851 (-2360 3135);
PAINT MONO (-2360 3135);
FORCEPROP 0 LASTPIN (-2350 3075) $PN CG35
J 2
(-2360 3085);
DISPLAY 0.680851 (-2360 3085);
PAINT MONO (-2360 3085);
FORCEPROP 0 LASTPIN (-2350 3025) $PN CM13
J 2
(-2360 3035);
DISPLAY 0.680851 (-2360 3035);
PAINT MONO (-2360 3035);
FORCEPROP 0 LASTPIN (-2350 2975) $PN CM22
J 2
(-2360 2985);
DISPLAY 0.680851 (-2360 2985);
PAINT MONO (-2360 2985);
FORCEPROP 0 LASTPIN (-2350 2925) $PN CM32
J 2
(-2360 2935);
DISPLAY 0.680851 (-2360 2935);
PAINT MONO (-2360 2935);
FORCEPROP 0 LASTPIN (-2350 2875) $PN CM4
J 2
(-2360 2885);
DISPLAY 0.680851 (-2360 2885);
PAINT MONO (-2360 2885);
FORCEPROP 0 LASTPIN (-2350 2825) $PN CN2
J 2
(-2360 2835);
DISPLAY 0.680851 (-2360 2835);
PAINT MONO (-2360 2835);
FORCEPROP 0 LASTPIN (-2350 2775) $PN CN34
J 2
(-2360 2785);
DISPLAY 0.680851 (-2360 2785);
PAINT MONO (-2360 2785);
FORCEPROP 0 LASTPIN (-2350 2725) $PN CP1
J 2
(-2360 2735);
DISPLAY 0.680851 (-2360 2735);
PAINT MONO (-2360 2735);
FORCEPROP 0 LASTPIN (-2350 2675) $PN CP35
J 2
(-2360 2685);
DISPLAY 0.680851 (-2360 2685);
PAINT MONO (-2360 2685);
FORCEPROP 0 LASTPIN (-2350 2625) $PN CW13
J 2
(-2360 2635);
DISPLAY 0.680851 (-2360 2635);
PAINT MONO (-2360 2635);
FORCEPROP 0 LASTPIN (-2350 2575) $PN CW22
J 2
(-2360 2585);
DISPLAY 0.680851 (-2360 2585);
PAINT MONO (-2360 2585);
FORCEPROP 0 LASTPIN (-2350 2525) $PN CW32
J 2
(-2360 2535);
DISPLAY 0.680851 (-2360 2535);
PAINT MONO (-2360 2535);
FORCEPROP 0 LASTPIN (-2350 2475) $PN CW4
J 2
(-2360 2485);
DISPLAY 0.680851 (-2360 2485);
PAINT MONO (-2360 2485);
FORCEPROP 0 LASTPIN (-2350 2425) $PN CY2
J 2
(-2360 2435);
DISPLAY 0.680851 (-2360 2435);
PAINT MONO (-2360 2435);
FORCEPROP 0 LASTPIN (-2350 2375) $PN CY34
J 2
(-2360 2385);
DISPLAY 0.680851 (-2360 2385);
PAINT MONO (-2360 2385);
FORCEPROP 0 LASTPIN (-2350 2325) $PN DA1
J 2
(-2360 2335);
DISPLAY 0.680851 (-2360 2335);
PAINT MONO (-2360 2335);
FORCEPROP 0 LASTPIN (-2350 2275) $PN DA35
J 2
(-2360 2285);
DISPLAY 0.680851 (-2360 2285);
PAINT MONO (-2360 2285);
FORCEPROP 0 LASTPIN (-2350 2225) $PN DF13
J 2
(-2360 2235);
DISPLAY 0.680851 (-2360 2235);
PAINT MONO (-2360 2235);
FORCEPROP 0 LASTPIN (-2350 2175) $PN DF22
J 2
(-2360 2185);
DISPLAY 0.680851 (-2360 2185);
PAINT MONO (-2360 2185);
FORCEPROP 0 LASTPIN (-2350 2125) $PN DF32
J 2
(-2360 2135);
DISPLAY 0.680851 (-2360 2135);
PAINT MONO (-2360 2135);
FORCEPROP 0 LASTPIN (-2350 2075) $PN DF4
J 2
(-2360 2085);
DISPLAY 0.680851 (-2360 2085);
PAINT MONO (-2360 2085);
FORCEPROP 0 LASTPIN (-2350 2025) $PN DG2
J 2
(-2360 2035);
DISPLAY 0.680851 (-2360 2035);
PAINT MONO (-2360 2035);
FORCEPROP 0 LASTPIN (-2350 1975) $PN DG34
J 2
(-2360 1985);
DISPLAY 0.680851 (-2360 1985);
PAINT MONO (-2360 1985);
FORCEPROP 0 LASTPIN (-2350 1925) $PN DH1
J 2
(-2360 1935);
DISPLAY 0.680851 (-2360 1935);
PAINT MONO (-2360 1935);
FORCEPROP 0 LASTPIN (-2350 1875) $PN DH35
J 2
(-2360 1885);
DISPLAY 0.680851 (-2360 1885);
PAINT MONO (-2360 1885);
FORCEPROP 0 LASTPIN (-2350 1825) $PN DN13
J 2
(-2360 1835);
DISPLAY 0.680851 (-2360 1835);
PAINT MONO (-2360 1835);
FORCEPROP 0 LASTPIN (-1400 5875) $PN DN22
J 0
(-1390 5885);
DISPLAY 0.680851 (-1390 5885);
PAINT MONO (-1390 5885);
FORCEPROP 0 LASTPIN (-1400 5825) $PN DN32
J 0
(-1390 5835);
DISPLAY 0.680851 (-1390 5835);
PAINT MONO (-1390 5835);
FORCEPROP 0 LASTPIN (-1400 5775) $PN DN4
J 0
(-1390 5785);
DISPLAY 0.680851 (-1390 5785);
PAINT MONO (-1390 5785);
FORCEPROP 0 LASTPIN (-1400 5725) $PN DP2
J 0
(-1390 5735);
DISPLAY 0.680851 (-1390 5735);
PAINT MONO (-1390 5735);
FORCEPROP 0 LASTPIN (-1400 5675) $PN DP34
J 0
(-1390 5685);
DISPLAY 0.680851 (-1390 5685);
PAINT MONO (-1390 5685);
FORCEPROP 0 LASTPIN (-1400 5625) $PN DR1
J 0
(-1390 5635);
DISPLAY 0.680851 (-1390 5635);
PAINT MONO (-1390 5635);
FORCEPROP 0 LASTPIN (-1400 5575) $PN DR35
J 0
(-1390 5585);
DISPLAY 0.680851 (-1390 5585);
PAINT MONO (-1390 5585);
FORCEPROP 0 LASTPIN (-1400 5525) $PN DY13
J 0
(-1390 5535);
DISPLAY 0.680851 (-1390 5535);
PAINT MONO (-1390 5535);
FORCEPROP 0 LASTPIN (-1400 5475) $PN DY22
J 0
(-1390 5485);
DISPLAY 0.680851 (-1390 5485);
PAINT MONO (-1390 5485);
FORCEPROP 0 LASTPIN (-1400 5425) $PN DY32
J 0
(-1390 5435);
DISPLAY 0.680851 (-1390 5435);
PAINT MONO (-1390 5435);
FORCEPROP 0 LASTPIN (-1400 5375) $PN DY4
J 0
(-1390 5385);
DISPLAY 0.680851 (-1390 5385);
PAINT MONO (-1390 5385);
FORCEPROP 0 LASTPIN (-1400 5325) $PN E14
J 0
(-1390 5335);
DISPLAY 0.680851 (-1390 5335);
PAINT MONO (-1390 5335);
FORCEPROP 0 LASTPIN (-1400 5275) $PN E27
J 0
(-1390 5285);
DISPLAY 0.680851 (-1390 5285);
PAINT MONO (-1390 5285);
FORCEPROP 0 LASTPIN (-1400 5225) $PN E33
J 0
(-1390 5235);
DISPLAY 0.680851 (-1390 5235);
PAINT MONO (-1390 5235);
FORCEPROP 0 LASTPIN (-1400 5175) $PN EA2
J 0
(-1390 5185);
DISPLAY 0.680851 (-1390 5185);
PAINT MONO (-1390 5185);
FORCEPROP 0 LASTPIN (-1400 5125) $PN EA34
J 0
(-1390 5135);
DISPLAY 0.680851 (-1390 5135);
PAINT MONO (-1390 5135);
FORCEPROP 0 LASTPIN (-1400 5075) $PN EB1
J 0
(-1390 5085);
DISPLAY 0.680851 (-1390 5085);
PAINT MONO (-1390 5085);
FORCEPROP 0 LASTPIN (-1400 5025) $PN EB35
J 0
(-1390 5035);
DISPLAY 0.680851 (-1390 5035);
PAINT MONO (-1390 5035);
FORCEPROP 0 LASTPIN (-1400 4975) $PN EG13
J 0
(-1390 4985);
DISPLAY 0.680851 (-1390 4985);
PAINT MONO (-1390 4985);
FORCEPROP 0 LASTPIN (-1400 4925) $PN EG22
J 0
(-1390 4935);
DISPLAY 0.680851 (-1390 4935);
PAINT MONO (-1390 4935);
FORCEPROP 0 LASTPIN (-1400 4875) $PN EG32
J 0
(-1390 4885);
DISPLAY 0.680851 (-1390 4885);
PAINT MONO (-1390 4885);
FORCEPROP 0 LASTPIN (-1400 4825) $PN EG4
J 0
(-1390 4835);
DISPLAY 0.680851 (-1390 4835);
PAINT MONO (-1390 4835);
FORCEPROP 0 LASTPIN (-1400 4775) $PN EH2
J 0
(-1390 4785);
DISPLAY 0.680851 (-1390 4785);
PAINT MONO (-1390 4785);
FORCEPROP 0 LASTPIN (-1400 4725) $PN EH34
J 0
(-1390 4735);
DISPLAY 0.680851 (-1390 4735);
PAINT MONO (-1390 4735);
FORCEPROP 0 LASTPIN (-1400 4675) $PN EJ1
J 0
(-1390 4685);
DISPLAY 0.680851 (-1390 4685);
PAINT MONO (-1390 4685);
FORCEPROP 0 LASTPIN (-1400 4625) $PN EJ35
J 0
(-1390 4635);
DISPLAY 0.680851 (-1390 4635);
PAINT MONO (-1390 4635);
FORCEPROP 0 LASTPIN (-1400 4575) $PN EP13
J 0
(-1390 4585);
DISPLAY 0.680851 (-1390 4585);
PAINT MONO (-1390 4585);
FORCEPROP 0 LASTPIN (-1400 4525) $PN EP22
J 0
(-1390 4535);
DISPLAY 0.680851 (-1390 4535);
PAINT MONO (-1390 4535);
FORCEPROP 0 LASTPIN (-1400 4475) $PN EP32
J 0
(-1390 4485);
DISPLAY 0.680851 (-1390 4485);
PAINT MONO (-1390 4485);
FORCEPROP 0 LASTPIN (-1400 4425) $PN EP4
J 0
(-1390 4435);
DISPLAY 0.680851 (-1390 4435);
PAINT MONO (-1390 4435);
FORCEPROP 0 LASTPIN (-1400 4375) $PN ER2
J 0
(-1390 4385);
DISPLAY 0.680851 (-1390 4385);
PAINT MONO (-1390 4385);
FORCEPROP 0 LASTPIN (-1400 4325) $PN ER34
J 0
(-1390 4335);
DISPLAY 0.680851 (-1390 4335);
PAINT MONO (-1390 4335);
FORCEPROP 0 LASTPIN (-1400 4275) $PN ET1
J 0
(-1390 4285);
DISPLAY 0.680851 (-1390 4285);
PAINT MONO (-1390 4285);
FORCEPROP 0 LASTPIN (-1400 4225) $PN ET35
J 0
(-1390 4235);
DISPLAY 0.680851 (-1390 4235);
PAINT MONO (-1390 4235);
FORCEPROP 0 LASTPIN (-1400 4175) $PN FA15
J 0
(-1390 4185);
DISPLAY 0.680851 (-1390 4185);
PAINT MONO (-1390 4185);
FORCEPROP 0 LASTPIN (-1400 4125) $PN FA32
J 0
(-1390 4135);
DISPLAY 0.680851 (-1390 4135);
PAINT MONO (-1390 4135);
FORCEPROP 0 LASTPIN (-1400 4075) $PN FB2
J 0
(-1390 4085);
DISPLAY 0.680851 (-1390 4085);
PAINT MONO (-1390 4085);
FORCEPROP 0 LASTPIN (-1400 4025) $PN FB34
J 0
(-1390 4035);
DISPLAY 0.680851 (-1390 4035);
PAINT MONO (-1390 4035);
FORCEPROP 0 LASTPIN (-1400 3975) $PN FC19
J 0
(-1390 3985);
DISPLAY 0.680851 (-1390 3985);
PAINT MONO (-1390 3985);
FORCEPROP 0 LASTPIN (-1400 3925) $PN FC23
J 0
(-1390 3935);
DISPLAY 0.680851 (-1390 3935);
PAINT MONO (-1390 3935);
FORCEPROP 0 LASTPIN (-1400 3875) $PN FC25
J 0
(-1390 3885);
DISPLAY 0.680851 (-1390 3885);
PAINT MONO (-1390 3885);
FORCEPROP 0 LASTPIN (-1400 3825) $PN FC28
J 0
(-1390 3835);
DISPLAY 0.680851 (-1390 3835);
PAINT MONO (-1390 3835);
FORCEPROP 0 LASTPIN (-1400 3775) $PN FC3
J 0
(-1390 3785);
DISPLAY 0.680851 (-1390 3785);
PAINT MONO (-1390 3785);
FORCEPROP 0 LASTPIN (-1400 3725) $PN FC6
J 0
(-1390 3735);
DISPLAY 0.680851 (-1390 3735);
PAINT MONO (-1390 3735);
FORCEPROP 0 LASTPIN (-1400 3675) $PN FC9
J 0
(-1390 3685);
DISPLAY 0.680851 (-1390 3685);
PAINT MONO (-1390 3685);
FORCEPROP 0 LASTPIN (-1400 3625) $PN FD1
J 0
(-1390 3635);
DISPLAY 0.680851 (-1390 3635);
PAINT MONO (-1390 3635);
FORCEPROP 0 LASTPIN (-1400 3575) $PN FD35
J 0
(-1390 3585);
DISPLAY 0.680851 (-1390 3585);
PAINT MONO (-1390 3585);
FORCEPROP 0 LASTPIN (-1400 3525) $PN FF14
J 0
(-1390 3535);
DISPLAY 0.680851 (-1390 3535);
PAINT MONO (-1390 3535);
FORCEPROP 0 LASTPIN (-1400 3475) $PN FF21
J 0
(-1390 3485);
DISPLAY 0.680851 (-1390 3485);
PAINT MONO (-1390 3485);
FORCEPROP 0 LASTPIN (-1400 3425) $PN FJ12
J 0
(-1390 3435);
DISPLAY 0.680851 (-1390 3435);
PAINT MONO (-1390 3435);
FORCEPROP 0 LASTPIN (-1400 3375) $PN FJ19
J 0
(-1390 3385);
DISPLAY 0.680851 (-1390 3385);
PAINT MONO (-1390 3385);
FORCEPROP 0 LASTPIN (-1400 3325) $PN H12
J 0
(-1390 3335);
DISPLAY 0.680851 (-1390 3335);
PAINT MONO (-1390 3335);
FORCEPROP 0 LASTPIN (-1400 3275) $PN H16
J 0
(-1390 3285);
DISPLAY 0.680851 (-1390 3285);
PAINT MONO (-1390 3285);
FORCEPROP 0 LASTPIN (-1400 3225) $PN H19
J 0
(-1390 3235);
DISPLAY 0.680851 (-1390 3235);
PAINT MONO (-1390 3235);
FORCEPROP 0 LASTPIN (-1400 3175) $PN H31
J 0
(-1390 3185);
DISPLAY 0.680851 (-1390 3185);
PAINT MONO (-1390 3185);
FORCEPROP 0 LASTPIN (-1400 3125) $PN J22
J 0
(-1390 3135);
DISPLAY 0.680851 (-1390 3135);
PAINT MONO (-1390 3135);
FORCEPROP 0 LASTPIN (-1400 3075) $PN J4
J 0
(-1390 3085);
DISPLAY 0.680851 (-1390 3085);
PAINT MONO (-1390 3085);
FORCEPROP 0 LASTPIN (-1400 3025) $PN K2
J 0
(-1390 3035);
DISPLAY 0.680851 (-1390 3035);
PAINT MONO (-1390 3035);
FORCEPROP 0 LASTPIN (-1400 2975) $PN K34
J 0
(-1390 2985);
DISPLAY 0.680851 (-1390 2985);
PAINT MONO (-1390 2985);
FORCEPROP 0 LASTPIN (-1400 2925) $PN L1
J 0
(-1390 2935);
DISPLAY 0.680851 (-1390 2935);
PAINT MONO (-1390 2935);
FORCEPROP 0 LASTPIN (-1400 2875) $PN L35
J 0
(-1390 2885);
DISPLAY 0.680851 (-1390 2885);
PAINT MONO (-1390 2885);
FORCEPROP 0 LASTPIN (-1400 2825) $PN T13
J 0
(-1390 2835);
DISPLAY 0.680851 (-1390 2835);
PAINT MONO (-1390 2835);
FORCEPROP 0 LASTPIN (-1400 2775) $PN T22
J 0
(-1390 2785);
DISPLAY 0.680851 (-1390 2785);
PAINT MONO (-1390 2785);
FORCEPROP 0 LASTPIN (-1400 2725) $PN T32
J 0
(-1390 2735);
DISPLAY 0.680851 (-1390 2735);
PAINT MONO (-1390 2735);
FORCEPROP 0 LASTPIN (-1400 2675) $PN T4
J 0
(-1390 2685);
DISPLAY 0.680851 (-1390 2685);
PAINT MONO (-1390 2685);
FORCEPROP 0 LASTPIN (-1400 2625) $PN U2
J 0
(-1390 2635);
DISPLAY 0.680851 (-1390 2635);
PAINT MONO (-1390 2635);
FORCEPROP 0 LASTPIN (-1400 2575) $PN U34
J 0
(-1390 2585);
DISPLAY 0.680851 (-1390 2585);
PAINT MONO (-1390 2585);
FORCEPROP 0 LASTPIN (-1400 2525) $PN V1
J 0
(-1390 2535);
DISPLAY 0.680851 (-1390 2535);
PAINT MONO (-1390 2535);
FORCEPROP 0 LASTPIN (-1400 2475) $PN V35
J 0
(-1390 2485);
DISPLAY 0.680851 (-1390 2485);
PAINT MONO (-1390 2485);
FORCEPROP 0 LASTPIN (-1400 2375) $PN A1
J 0
(-1390 2385);
DISPLAY 0.680851 (-1390 2385);
PAINT MONO (-1390 2385);
FORCEPROP 0 LASTPIN (-1400 2325) $PN A35
J 0
(-1390 2335);
DISPLAY 0.680851 (-1390 2335);
PAINT MONO (-1390 2335);
FORCEPROP 0 LASTPIN (-1400 2275) $PN C2
J 0
(-1390 2285);
DISPLAY 0.680851 (-1390 2285);
PAINT MONO (-1390 2285);
FORCEPROP 0 LASTPIN (-1400 2225) $PN C34
J 0
(-1390 2235);
DISPLAY 0.680851 (-1390 2235);
PAINT MONO (-1390 2235);
FORCEPROP 0 LASTPIN (-1400 2175) $PN D1
J 0
(-1390 2185);
DISPLAY 0.680851 (-1390 2185);
PAINT MONO (-1390 2185);
FORCEPROP 0 LASTPIN (-1400 2125) $PN D35
J 0
(-1390 2135);
DISPLAY 0.680851 (-1390 2135);
PAINT MONO (-1390 2135);
FORCEPROP 0 LASTPIN (-1400 2075) $PN FE2
J 0
(-1390 2085);
DISPLAY 0.680851 (-1390 2085);
PAINT MONO (-1390 2085);
FORCEPROP 0 LASTPIN (-1400 2025) $PN FE34
J 0
(-1390 2035);
DISPLAY 0.680851 (-1390 2035);
PAINT MONO (-1390 2035);
FORCEPROP 0 LASTPIN (-1400 1975) $PN FG1
J 0
(-1390 1985);
DISPLAY 0.680851 (-1390 1985);
PAINT MONO (-1390 1985);
FORCEPROP 0 LASTPIN (-1400 1925) $PN FG35
J 0
(-1390 1935);
DISPLAY 0.680851 (-1390 1935);
PAINT MONO (-1390 1935);
FORCEPROP 0 LASTPIN (-1400 1875) $PN FH2
J 0
(-1390 1885);
DISPLAY 0.680851 (-1390 1885);
PAINT MONO (-1390 1885);
FORCEPROP 0 LASTPIN (-1400 1825) $PN FH34
J 0
(-1390 1835);
DISPLAY 0.680851 (-1390 1835);
PAINT MONO (-1390 1835);
FORCEPROP 2 LAST PART_TYPE SMLF
J 0
(-2200 6300);
DISPLAY 0.680851 (-2200 6300);
FORCEPROP 2 LAST VALUE PT5161LRS
J 0
(-2200 6250);
DISPLAY 0.680851 (-2200 6250);
FORCEPROP 1 LAST MATERIAL IC
J 0
(-2200 6050);
DISPLAY 0.723404 (-2200 6050);
PAINT GREEN (-2200 6050);
FORCEPROP 1 LAST NEEDS_NO_SIZE TRUE
J 0
(-1850 3875);
DISPLAY 0.723404 (-1850 3875);
PAINT GREEN (-1850 3875);
DISPLAY INVISIBLE (-1850 3875);
FORCEPROP 1 LAST CDS_LMAN_SYM_OUTLINE -350,2150,300,-2150
J 0
(-1850 3875);
DISPLAY 0.468085 (-1850 3875);
PAINT GREEN (-1850 3875);
DISPLAY INVISIBLE (-1850 3875);
FORCEPROP 2 LAST CDS_LIB pure_quanta
J 0
(-1850 3875);
DISPLAY INVISIBLE (-1850 3875);
FORCEPROP 1 LAST PATH I2
J 0
(-1850 3875);
DISPLAY 0.723404 (-1850 3875);
PAINT GREEN (-1850 3875);
DISPLAY INVISIBLE (-1850 3875);
FORCEPROP 1 LAST PART_NUMBER AJ051610U03
J 0
(-2200 6125);
DISPLAY 0.723404 (-2200 6125);
PAINT GREEN (-2200 6125);
DISPLAY INVISIBLE (-2200 6125);
FORCEADD P1V0..1
(-7775 4700);
FORCEPROP 3 LASTPIN (-7775 4650) SIG_NAME P1V8_CPU1_RT0_1A_1D\g
J 0
(-7765 4660);
DISPLAY 0.659574 (-7765 4660);
PAINT MONO (-7765 4660);
DISPLAY INVISIBLE (-7765 4660);
FORCEPROP 1 LAST HDL_POWER P1V8_CPU1_RT0_1A_1D
J 1
(-7775 4750);
DISPLAY 0.489362 (-7775 4750);
PAINT SKYBLUE (-7775 4750);
FORCEPROP 2 LAST CDS_LIB pure_quanta_power
J 0
(-7775 4700);
DISPLAY INVISIBLE (-7775 4700);
FORCEPROP 1 LAST PATH I21
J 0
(-7725 4725);
DISPLAY 0.872340 (-7725 4725);
PAINT AQUA (-7725 4725);
DISPLAY INVISIBLE (-7725 4725);
FORCEADD UNIVERSAL_GND..1
(-7075 3400);
FORCEPROP 3 LASTPIN (-7075 3450) SIG_NAME GND\g
J 0
(-7065 3460);
DISPLAY 0.659574 (-7065 3460);
PAINT MONO (-7065 3460);
DISPLAY INVISIBLE (-7065 3460);
FORCEPROP 2 LAST CDS_LIB pure_quanta_power
J 0
(-7075 3400);
DISPLAY INVISIBLE (-7075 3400);
FORCEPROP 1 LAST HDL_POWER GND
J 1
(-7050 3325);
DISPLAY 0.872340 (-7050 3325);
PAINT GREEN (-7050 3325);
DISPLAY INVISIBLE (-7050 3325);
FORCEPROP 1 LAST PATH I25
J 0
(-7000 3400);
DISPLAY 0.872340 (-7000 3400);
PAINT AQUA (-7000 3400);
DISPLAY INVISIBLE (-7000 3400);
FORCEADD P1V0..1
(-8100 4425);
FORCEPROP 3 LASTPIN (-8100 4375) SIG_NAME P1V8_CPU1_RT_1D\g
J 0
(-8090 4385);
DISPLAY 0.659574 (-8090 4385);
PAINT MONO (-8090 4385);
DISPLAY INVISIBLE (-8090 4385);
FORCEPROP 1 LAST HDL_POWER P1V8_CPU1_RT_1D
J 1
(-8100 4475);
DISPLAY 0.489362 (-8100 4475);
PAINT SKYBLUE (-8100 4475);
FORCEPROP 2 LAST CDS_LIB pure_quanta_power
J 0
(-8100 4425);
DISPLAY INVISIBLE (-8100 4425);
FORCEPROP 1 LAST PATH I27
J 0
(-8050 4450);
DISPLAY 0.872340 (-8050 4450);
PAINT AQUA (-8050 4450);
DISPLAY INVISIBLE (-8050 4450);
FORCEADD UNIVERSAL_GND..1
(-2550 1625);
FORCEPROP 3 LASTPIN (-2550 1675) SIG_NAME GND\g
J 0
(-2540 1685);
DISPLAY 0.659574 (-2540 1685);
PAINT MONO (-2540 1685);
DISPLAY INVISIBLE (-2540 1685);
FORCEPROP 2 LAST CDS_LIB pure_quanta_power
J 0
(-2550 1625);
DISPLAY INVISIBLE (-2550 1625);
FORCEPROP 1 LAST HDL_POWER GND
J 1
(-2525 1550);
DISPLAY 0.872340 (-2525 1550);
PAINT GREEN (-2525 1550);
DISPLAY INVISIBLE (-2525 1550);
FORCEPROP 1 LAST PATH I3
J 0
(-2475 1625);
DISPLAY 0.872340 (-2475 1625);
PAINT AQUA (-2475 1625);
DISPLAY INVISIBLE (-2475 1625);
FORCEADD UNIVERSAL_GND..1
(-500 2350);
FORCEPROP 3 LASTPIN (-500 2400) SIG_NAME GND\g
J 0
(-490 2410);
DISPLAY 0.659574 (-490 2410);
PAINT MONO (-490 2410);
DISPLAY INVISIBLE (-490 2410);
FORCEPROP 2 LAST CDS_LIB pure_quanta_power
J 0
(-500 2350);
DISPLAY INVISIBLE (-500 2350);
FORCEPROP 1 LAST HDL_POWER GND
J 1
(-475 2275);
DISPLAY 0.872340 (-475 2275);
PAINT GREEN (-475 2275);
DISPLAY INVISIBLE (-475 2275);
FORCEPROP 1 LAST PATH I4
J 0
(-425 2350);
DISPLAY 0.872340 (-425 2350);
PAINT AQUA (-425 2350);
DISPLAY INVISIBLE (-425 2350);
FORCEADD VCC_CORE..1
(-4100 5325);
FORCEPROP 3 LASTPIN (-4100 5275) SIG_NAME P0V9_CPU1_RT0_2A\g
J 0
(-4090 5285);
DISPLAY 0.659574 (-4090 5285);
PAINT MONO (-4090 5285);
DISPLAY INVISIBLE (-4090 5285);
FORCEPROP 1 LAST HDL_POWER P0V9_CPU1_RT0_2A
J 1
(-4100 5375);
DISPLAY 0.617021 (-4100 5375);
PAINT GREEN (-4100 5375);
FORCEPROP 2 LAST CDS_LIB pure_quanta_power
J 0
(-4100 5325);
DISPLAY INVISIBLE (-4100 5325);
FORCEPROP 1 LAST PATH I40
J 0
(-4050 5350);
DISPLAY 0.872340 (-4050 5350);
PAINT AQUA (-4050 5350);
DISPLAY INVISIBLE (-4050 5350);
FORCEADD UNIVERSAL_GND..1
(-875 1250);
FORCEPROP 3 LASTPIN (-875 1300) SIG_NAME GND\g
J 0
(-865 1310);
DISPLAY 0.659574 (-865 1310);
PAINT MONO (-865 1310);
DISPLAY INVISIBLE (-865 1310);
FORCEPROP 2 LAST CDS_LIB pure_quanta_power
J 0
(-875 1250);
DISPLAY INVISIBLE (-875 1250);
FORCEPROP 1 LAST HDL_POWER GND
J 1
(-850 1175);
DISPLAY 0.872340 (-850 1175);
PAINT GREEN (-850 1175);
DISPLAY INVISIBLE (-850 1175);
FORCEPROP 1 LAST PATH I6
J 0
(-800 1250);
DISPLAY 0.872340 (-800 1250);
PAINT AQUA (-800 1250);
DISPLAY INVISIBLE (-800 1250);
FORCEADD P1V0..1
(-4075 4100);
FORCEPROP 3 LASTPIN (-4075 4050) SIG_NAME P0V9_CPU1_RT_2D\g
J 0
(-4065 4060);
DISPLAY 0.659574 (-4065 4060);
PAINT MONO (-4065 4060);
DISPLAY INVISIBLE (-4065 4060);
FORCEPROP 1 LAST HDL_POWER P0V9_CPU1_RT_2D
J 1
(-4075 4150);
DISPLAY 0.489362 (-4075 4150);
PAINT SKYBLUE (-4075 4150);
FORCEPROP 2 LAST CDS_LIB pure_quanta_power
J 0
(-4075 4100);
DISPLAY INVISIBLE (-4075 4100);
FORCEPROP 1 LAST PATH I61
J 0
(-4025 4125);
DISPLAY 0.872340 (-4025 4125);
PAINT AQUA (-4025 4125);
DISPLAY INVISIBLE (-4025 4125);
FORCEADD UNIVERSAL_GND..1
(-725 1800);
FORCEPROP 3 LASTPIN (-725 1850) SIG_NAME GND\g
J 0
(-715 1860);
DISPLAY 0.659574 (-715 1860);
PAINT MONO (-715 1860);
DISPLAY INVISIBLE (-715 1860);
FORCEPROP 2 LAST CDS_LIB pure_quanta_power
J 0
(-725 1800);
DISPLAY INVISIBLE (-725 1800);
FORCEPROP 1 LAST HDL_POWER GND
J 1
(-700 1725);
DISPLAY 0.872340 (-700 1725);
PAINT GREEN (-700 1725);
DISPLAY INVISIBLE (-700 1725);
FORCEPROP 1 LAST PATH I8
J 0
(-650 1800);
DISPLAY 0.872340 (-650 1800);
PAINT AQUA (-650 1800);
DISPLAY INVISIBLE (-650 1800);
FORCEADD VCC_CORE..1
(-4675 4850);
FORCEPROP 3 LASTPIN (-4675 4800) SIG_NAME P0V9_CPU1_RT0_2A_2D\g
J 0
(-4665 4810);
DISPLAY 0.659574 (-4665 4810);
PAINT MONO (-4665 4810);
DISPLAY INVISIBLE (-4665 4810);
FORCEPROP 1 LAST HDL_POWER P0V9_CPU1_RT0_2A_2D
J 1
(-4675 4900);
DISPLAY 0.617021 (-4675 4900);
PAINT GREEN (-4675 4900);
FORCEPROP 2 LAST CDS_LIB pure_quanta_power
J 0
(-4675 4850);
DISPLAY INVISIBLE (-4675 4850);
FORCEPROP 1 LAST PATH I97
J 0
(-4625 4875);
DISPLAY 0.872340 (-4625 4875);
PAINT AQUA (-4625 4875);
DISPLAY INVISIBLE (-4625 4875);
FORCEADD P1V0..1
(-7200 5150);
FORCEPROP 3 LASTPIN (-7200 5100) SIG_NAME P1V8_CPU1_RT0_1A\g
J 0
(-7190 5110);
DISPLAY 0.659574 (-7190 5110);
PAINT MONO (-7190 5110);
DISPLAY INVISIBLE (-7190 5110);
FORCEPROP 1 LAST HDL_POWER P1V8_CPU1_RT0_1A
J 1
(-7200 5200);
DISPLAY 0.489362 (-7200 5200);
PAINT SKYBLUE (-7200 5200);
FORCEPROP 2 LAST CDS_LIB pure_quanta_power
J 0
(-7200 5150);
DISPLAY INVISIBLE (-7200 5150);
FORCEPROP 1 LAST PATH I98
J 0
(-7150 5175);
DISPLAY 0.872340 (-7150 5175);
PAINT AQUA (-7150 5175);
DISPLAY INVISIBLE (-7150 5175);
FORCEADD DNS..2
(-8025 4200);
PAINT RED (-8025 4200);
FORCEPROP 2 LAST CDS_LIB mstr_misc
J 0
(-8025 4200);
DISPLAY INVISIBLE (-8025 4200);
FORCEPROP 1 LAST COMMENT_BODY TRUE
J 0
(-8025 4200);
DISPLAY INVISIBLE (-8025 4200);
FORCEADD QUANTA_TITLE_BLOCK_C..1
(0 0);
FORCEPROP 0 LAST CDS_CON_LAST_MODIFIED Thu Sep 14 16:12:51 2023
J 0
(-1885 15);
DISPLAY INVISIBLE (-1885 15);
FORCEPROP 1 LAST CUSTOM_TXT_CDS <CON_LAST_MODIFIED>
J 0
(-1885 15);
DISPLAY 0.978723 (-1885 15);
FORCEPROP 2 LAST CUSTOM_TXT_CDS <XR_PAGE_TITLE>
J 0
(-7890 5250);
DISPLAY 0.638298 (-7890 5250);
PAINT PINK (-7890 5250);
DISPLAY INVISIBLE (-7890 5250);
FORCEPROP 1 LAST CUSTOM_TXT_CDS <NAME_2>
J 0
(-3175 50);
FORCEPROP 1 LAST CUSTOM_TXT_CDS <NAME_1>
J 0
(-3175 175);
FORCEPROP 1 LAST CUSTOM_TXT_CDS <Q_NUMBER>
J 0
(-1403 103);
DISPLAY 1.212766 (-1403 103);
FORCEPROP 1 LAST CUSTOM_TXT_CDS <Q_PROJ>
J 0
(-2382 102);
DISPLAY 1.212766 (-2382 102);
FORCEPROP 1 LAST CUSTOM_TXT_CDS <Q_REV>
J 0
(-184 103);
DISPLAY 1.212766 (-184 103);
FORCEPROP 1 LAST CUSTOM_TXT_CDS <CON_PAGE_NUM> OF <CON_TOTAL_PAGES>
J 0
(-446 18);
DISPLAY 0.978723 (-446 18);
FORCEPROP 1 LAST Q_TITLE RETIMER_CPU1_P0 POWER(6)
J 0
(-9366 26);
DISPLAY 2.446809 (-9366 26);
PAINT GREEN (-9366 26);
FORCEPROP 2 LAST PAGE_BORDER TRUE
J 0
(-7890 5250);
DISPLAY 0.638298 (-7890 5250);
PAINT PINK (-7890 5250);
DISPLAY INVISIBLE (-7890 5250);
FORCEPROP 1 LAST CDS_LMAN_SYM_OUTLINE -9475,6775,100,-125
J 0
(0 0);
DISPLAY 0.468085 (0 0);
PAINT GREEN (0 0);
DISPLAY INVISIBLE (0 0);
FORCEPROP 2 LAST CDS_LIB pure_quanta
J 0
(0 0);
DISPLAY INVISIBLE (0 0);
FORCEPROP 2 LAST CDS_XR_PAGE_TITLE CR-322 : @T6G_MB_LIB.T6G(SCH_1):PAGE322
J 0
(-7890 5250);
DISPLAY 0.638298 (-7890 5250);
PAINT PINK (-7890 5250);
DISPLAY INVISIBLE (-7890 5250);
FORCEPROP 1 LAST Q_DEPT BU9
J 1
(-3763 49);
DISPLAY 1.957447 (-3763 49);
PAINT GREEN (-3763 49);
DISPLAY INVISIBLE (-3763 49);
FORCEPROP 1 LAST COMMENT_BODY TRUE
J 0
(12 -13);
DISPLAY 0.978723 (12 -13);
PAINT GREEN (12 -13);
DISPLAY INVISIBLE (12 -13);
WIRE 16 -1 (-7075 3550)(-7075 3450);
WIRE 16 -1 (-8100 4375)(-8100 4300);
WIRE 16 -1 (-875 1450)(-875 1300);
WIRE 16 -1 (-725 2000)(-725 1850);
WIRE 16 -1 (-6525 3950)(-7075 3950);
WIRE 16 -1 (-7075 3950)(-7075 3750);
WIRE 16 -1 (-7075 3950)(-8100 3950);
FORCEPROP 2 LAST SIG_NAME RT_CPU1_P0_VQPS
J 0
(-7285 3960);
DISPLAY 0.680851 (-7285 3960);
PAINT SKYBLUE (-7285 3960);
FORCEPROP 2 LASTPROP $XRERR UNIQUE?
J 0
(-7525 3960);
DISPLAY 0.638298 (-7525 3960);
PAINT MONO (-7525 3960);
DISPLAY INVISIBLE (-7525 3960);
WIRE 16 -1 (-8100 4100)(-8100 3950);
WIRE 16 -1 (-2350 1875)(-2550 1875);
WIRE 16 -1 (-2550 1925)(-2550 1875);
WIRE 16 -1 (-2550 1875)(-2550 1825);
WIRE 16 -1 (-2350 1825)(-2550 1825);
WIRE 16 -1 (-2550 1825)(-2550 1675);
WIRE 16 -1 (-2350 1925)(-2550 1925);
WIRE 16 -1 (-2550 1975)(-2550 1925);
WIRE 16 -1 (-2350 1975)(-2550 1975);
WIRE 16 -1 (-2550 2025)(-2550 1975);
WIRE 16 -1 (-2550 2075)(-2550 2025);
WIRE 16 -1 (-2350 2025)(-2550 2025);
WIRE 16 -1 (-2350 2075)(-2550 2075);
WIRE 16 -1 (-2550 2125)(-2550 2075);
WIRE 16 -1 (-2350 2125)(-2550 2125);
WIRE 16 -1 (-2550 2175)(-2550 2125);
WIRE 16 -1 (-2350 2175)(-2550 2175);
WIRE 16 -1 (-2550 2225)(-2550 2175);
WIRE 16 -1 (-2350 2225)(-2550 2225);
WIRE 16 -1 (-2550 2275)(-2550 2225);
WIRE 16 -1 (-2550 2325)(-2550 2275);
WIRE 16 -1 (-2350 2275)(-2550 2275);
WIRE 16 -1 (-2350 2325)(-2550 2325);
WIRE 16 -1 (-2550 2375)(-2550 2325);
WIRE 16 -1 (-2350 2375)(-2550 2375);
WIRE 16 -1 (-2550 2425)(-2550 2375);
WIRE 16 -1 (-2350 2425)(-2550 2425);
WIRE 16 -1 (-2550 2475)(-2550 2425);
WIRE 16 -1 (-2350 2475)(-2550 2475);
WIRE 16 -1 (-2550 2525)(-2550 2475);
WIRE 16 -1 (-2550 2575)(-2550 2525);
WIRE 16 -1 (-2350 2525)(-2550 2525);
WIRE 16 -1 (-2350 2575)(-2550 2575);
WIRE 16 -1 (-2550 2625)(-2550 2575);
WIRE 16 -1 (-2350 2625)(-2550 2625);
WIRE 16 -1 (-2550 2675)(-2550 2625);
WIRE 16 -1 (-2350 2675)(-2550 2675);
WIRE 16 -1 (-2550 2725)(-2550 2675);
WIRE 16 -1 (-2350 2725)(-2550 2725);
WIRE 16 -1 (-2550 2775)(-2550 2725);
WIRE 16 -1 (-2550 2825)(-2550 2775);
WIRE 16 -1 (-2350 2775)(-2550 2775);
WIRE 16 -1 (-2350 2825)(-2550 2825);
WIRE 16 -1 (-2550 2875)(-2550 2825);
WIRE 16 -1 (-2350 2875)(-2550 2875);
WIRE 16 -1 (-2550 2925)(-2550 2875);
WIRE 16 -1 (-2350 2925)(-2550 2925);
WIRE 16 -1 (-2550 2975)(-2550 2925);
WIRE 16 -1 (-2350 2975)(-2550 2975);
WIRE 16 -1 (-2550 3025)(-2550 2975);
WIRE 16 -1 (-2550 3075)(-2550 3025);
WIRE 16 -1 (-2350 3025)(-2550 3025);
WIRE 16 -1 (-2350 3075)(-2550 3075);
WIRE 16 -1 (-2550 3125)(-2550 3075);
WIRE 16 -1 (-2350 3125)(-2550 3125);
WIRE 16 -1 (-2550 3175)(-2550 3125);
WIRE 16 -1 (-2350 3175)(-2550 3175);
WIRE 16 -1 (-2550 3225)(-2550 3175);
WIRE 16 -1 (-2350 3225)(-2550 3225);
WIRE 16 -1 (-2550 3275)(-2550 3225);
WIRE 16 -1 (-2350 3275)(-2550 3275);
WIRE 16 -1 (-2550 3325)(-2550 3275);
WIRE 16 -1 (-2550 3375)(-2550 3325);
WIRE 16 -1 (-2350 3325)(-2550 3325);
WIRE 16 -1 (-2350 3375)(-2550 3375);
WIRE 16 -1 (-2550 3425)(-2550 3375);
WIRE 16 -1 (-2350 3425)(-2550 3425);
WIRE 16 -1 (-2550 3475)(-2550 3425);
WIRE 16 -1 (-2350 3475)(-2550 3475);
WIRE 16 -1 (-2550 3525)(-2550 3475);
WIRE 16 -1 (-2350 3525)(-2550 3525);
WIRE 16 -1 (-2550 3575)(-2550 3525);
WIRE 16 -1 (-2550 3625)(-2550 3575);
WIRE 16 -1 (-2350 3575)(-2550 3575);
WIRE 16 -1 (-2350 3625)(-2550 3625);
WIRE 16 -1 (-2550 3675)(-2550 3625);
WIRE 16 -1 (-2350 3675)(-2550 3675);
WIRE 16 -1 (-2550 3725)(-2550 3675);
WIRE 16 -1 (-2350 3725)(-2550 3725);
WIRE 16 -1 (-2550 3775)(-2550 3725);
WIRE 16 -1 (-2350 3775)(-2550 3775);
WIRE 16 -1 (-2550 3825)(-2550 3775);
WIRE 16 -1 (-2550 3875)(-2550 3825);
WIRE 16 -1 (-2350 3825)(-2550 3825);
WIRE 16 -1 (-2350 3875)(-2550 3875);
WIRE 16 -1 (-2550 3925)(-2550 3875);
WIRE 16 -1 (-2350 3925)(-2550 3925);
WIRE 16 -1 (-2550 3975)(-2550 3925);
WIRE 16 -1 (-2350 3975)(-2550 3975);
WIRE 16 -1 (-2550 4025)(-2550 3975);
WIRE 16 -1 (-2350 4025)(-2550 4025);
WIRE 16 -1 (-2550 4075)(-2550 4025);
WIRE 16 -1 (-2550 4125)(-2550 4075);
WIRE 16 -1 (-2350 4075)(-2550 4075);
WIRE 16 -1 (-2350 4125)(-2550 4125);
WIRE 16 -1 (-2550 4175)(-2550 4125);
WIRE 16 -1 (-2350 4175)(-2550 4175);
WIRE 16 -1 (-2550 4225)(-2550 4175);
WIRE 16 -1 (-2350 4225)(-2550 4225);
WIRE 16 -1 (-2550 4275)(-2550 4225);
WIRE 16 -1 (-2350 4275)(-2550 4275);
WIRE 16 -1 (-2550 4325)(-2550 4275);
WIRE 16 -1 (-2550 4375)(-2550 4325);
WIRE 16 -1 (-2350 4325)(-2550 4325);
WIRE 16 -1 (-2350 4375)(-2550 4375);
WIRE 16 -1 (-2550 4425)(-2550 4375);
WIRE 16 -1 (-2350 4425)(-2550 4425);
WIRE 16 -1 (-2550 4475)(-2550 4425);
WIRE 16 -1 (-2350 4475)(-2550 4475);
WIRE 16 -1 (-2550 4525)(-2550 4475);
WIRE 16 -1 (-2350 4525)(-2550 4525);
WIRE 16 -1 (-2550 4575)(-2550 4525);
WIRE 16 -1 (-2550 4625)(-2550 4575);
WIRE 16 -1 (-2350 4575)(-2550 4575);
WIRE 16 -1 (-2350 4625)(-2550 4625);
WIRE 16 -1 (-2550 4675)(-2550 4625);
WIRE 16 -1 (-2350 4675)(-2550 4675);
WIRE 16 -1 (-2550 4725)(-2550 4675);
WIRE 16 -1 (-2350 4725)(-2550 4725);
WIRE 16 -1 (-2550 4775)(-2550 4725);
WIRE 16 -1 (-2350 4775)(-2550 4775);
WIRE 16 -1 (-2550 4825)(-2550 4775);
WIRE 16 -1 (-2550 4875)(-2550 4825);
WIRE 16 -1 (-2350 4825)(-2550 4825);
WIRE 16 -1 (-2350 4875)(-2550 4875);
WIRE 16 -1 (-2550 4925)(-2550 4875);
WIRE 16 -1 (-2350 4925)(-2550 4925);
WIRE 16 -1 (-2550 4975)(-2550 4925);
WIRE 16 -1 (-2350 4975)(-2550 4975);
WIRE 16 -1 (-2550 5025)(-2550 4975);
WIRE 16 -1 (-2350 5025)(-2550 5025);
WIRE 16 -1 (-2550 5075)(-2550 5025);
WIRE 16 -1 (-2550 5125)(-2550 5075);
WIRE 16 -1 (-2350 5075)(-2550 5075);
WIRE 16 -1 (-2350 5125)(-2550 5125);
WIRE 16 -1 (-2550 5175)(-2550 5125);
WIRE 16 -1 (-2350 5175)(-2550 5175);
WIRE 16 -1 (-2550 5225)(-2550 5175);
WIRE 16 -1 (-2350 5225)(-2550 5225);
WIRE 16 -1 (-2550 5275)(-2550 5225);
WIRE 16 -1 (-2350 5275)(-2550 5275);
WIRE 16 -1 (-2550 5325)(-2550 5275);
WIRE 16 -1 (-2350 5325)(-2550 5325);
WIRE 16 -1 (-2550 5375)(-2550 5325);
WIRE 16 -1 (-2550 5425)(-2550 5375);
WIRE 16 -1 (-2350 5375)(-2550 5375);
WIRE 16 -1 (-2350 5425)(-2550 5425);
WIRE 16 -1 (-2550 5475)(-2550 5425);
WIRE 16 -1 (-2350 5475)(-2550 5475);
WIRE 16 -1 (-2550 5525)(-2550 5475);
WIRE 16 -1 (-2350 5525)(-2550 5525);
WIRE 16 -1 (-2550 5575)(-2550 5525);
WIRE 16 -1 (-2350 5575)(-2550 5575);
WIRE 16 -1 (-2550 5625)(-2550 5575);
WIRE 16 -1 (-2550 5675)(-2550 5625);
WIRE 16 -1 (-2350 5625)(-2550 5625);
WIRE 16 -1 (-2350 5675)(-2550 5675);
WIRE 16 -1 (-2550 5725)(-2550 5675);
WIRE 16 -1 (-2350 5725)(-2550 5725);
WIRE 16 -1 (-2550 5775)(-2550 5725);
WIRE 16 -1 (-2350 5775)(-2550 5775);
WIRE 16 -1 (-2550 5825)(-2550 5775);
WIRE 16 -1 (-2350 5825)(-2550 5825);
WIRE 16 -1 (-2550 5875)(-2550 5825);
WIRE 16 -1 (-2350 5875)(-2550 5875);
WIRE 16 -1 (-1200 2475)(-1200 2450);
WIRE 16 -1 (-1200 2525)(-1200 2475);
WIRE 16 -1 (-1200 2475)(-1400 2475);
WIRE 16 -1 (-1200 2450)(-500 2450);
WIRE 16 -1 (-500 2450)(-500 2400);
WIRE 16 -1 (-1200 2575)(-1200 2525);
WIRE 16 -1 (-1200 2525)(-1400 2525);
WIRE 16 -1 (-1200 2625)(-1200 2575);
WIRE 16 -1 (-1200 2575)(-1400 2575);
WIRE 16 -1 (-1200 2675)(-1200 2625);
WIRE 16 -1 (-1200 2625)(-1400 2625);
WIRE 16 -1 (-1200 2725)(-1200 2675);
WIRE 16 -1 (-1200 2675)(-1400 2675);
WIRE 16 -1 (-1200 2775)(-1200 2725);
WIRE 16 -1 (-1200 2725)(-1400 2725);
WIRE 16 -1 (-1200 2825)(-1200 2775);
WIRE 16 -1 (-1200 2775)(-1400 2775);
WIRE 16 -1 (-1200 2875)(-1200 2825);
WIRE 16 -1 (-1200 2825)(-1400 2825);
WIRE 16 -1 (-1200 2925)(-1200 2875);
WIRE 16 -1 (-1200 2875)(-1400 2875);
WIRE 16 -1 (-1200 2975)(-1200 2925);
WIRE 16 -1 (-1200 2925)(-1400 2925);
WIRE 16 -1 (-1200 3025)(-1200 2975);
WIRE 16 -1 (-1200 2975)(-1400 2975);
WIRE 16 -1 (-1200 3075)(-1200 3025);
WIRE 16 -1 (-1200 3025)(-1400 3025);
WIRE 16 -1 (-1200 3125)(-1200 3075);
WIRE 16 -1 (-1200 3075)(-1400 3075);
WIRE 16 -1 (-1200 3175)(-1200 3125);
WIRE 16 -1 (-1200 3125)(-1400 3125);
WIRE 16 -1 (-1200 3225)(-1200 3175);
WIRE 16 -1 (-1200 3175)(-1400 3175);
WIRE 16 -1 (-1200 3275)(-1200 3225);
WIRE 16 -1 (-1200 3225)(-1400 3225);
WIRE 16 -1 (-1200 3325)(-1200 3275);
WIRE 16 -1 (-1200 3275)(-1400 3275);
WIRE 16 -1 (-1200 3375)(-1200 3325);
WIRE 16 -1 (-1200 3325)(-1400 3325);
WIRE 16 -1 (-1200 3425)(-1200 3375);
WIRE 16 -1 (-1200 3375)(-1400 3375);
WIRE 16 -1 (-1200 3475)(-1200 3425);
WIRE 16 -1 (-1200 3425)(-1400 3425);
WIRE 16 -1 (-1200 3525)(-1200 3475);
WIRE 16 -1 (-1200 3475)(-1400 3475);
WIRE 16 -1 (-1200 3575)(-1200 3525);
WIRE 16 -1 (-1200 3525)(-1400 3525);
WIRE 16 -1 (-1200 3625)(-1200 3575);
WIRE 16 -1 (-1200 3575)(-1400 3575);
WIRE 16 -1 (-1200 3675)(-1200 3625);
WIRE 16 -1 (-1200 3625)(-1400 3625);
WIRE 16 -1 (-1200 3725)(-1200 3675);
WIRE 16 -1 (-1200 3675)(-1400 3675);
WIRE 16 -1 (-1200 3775)(-1200 3725);
WIRE 16 -1 (-1200 3725)(-1400 3725);
WIRE 16 -1 (-1200 3825)(-1200 3775);
WIRE 16 -1 (-1200 3775)(-1400 3775);
WIRE 16 -1 (-1200 3875)(-1200 3825);
WIRE 16 -1 (-1200 3825)(-1400 3825);
WIRE 16 -1 (-1200 3925)(-1200 3875);
WIRE 16 -1 (-1200 3875)(-1400 3875);
WIRE 16 -1 (-1200 3975)(-1200 3925);
WIRE 16 -1 (-1200 3925)(-1400 3925);
WIRE 16 -1 (-1200 4025)(-1200 3975);
WIRE 16 -1 (-1200 3975)(-1400 3975);
WIRE 16 -1 (-1200 4075)(-1200 4025);
WIRE 16 -1 (-1200 4025)(-1400 4025);
WIRE 16 -1 (-1200 4125)(-1200 4075);
WIRE 16 -1 (-1200 4075)(-1400 4075);
WIRE 16 -1 (-1200 4175)(-1200 4125);
WIRE 16 -1 (-1200 4125)(-1400 4125);
WIRE 16 -1 (-1200 4225)(-1200 4175);
WIRE 16 -1 (-1200 4175)(-1400 4175);
WIRE 16 -1 (-1200 4275)(-1200 4225);
WIRE 16 -1 (-1200 4225)(-1400 4225);
WIRE 16 -1 (-1200 4325)(-1200 4275);
WIRE 16 -1 (-1200 4275)(-1400 4275);
WIRE 16 -1 (-1200 4375)(-1200 4325);
WIRE 16 -1 (-1200 4325)(-1400 4325);
WIRE 16 -1 (-1200 4425)(-1200 4375);
WIRE 16 -1 (-1200 4375)(-1400 4375);
WIRE 16 -1 (-1200 4475)(-1200 4425);
WIRE 16 -1 (-1200 4425)(-1400 4425);
WIRE 16 -1 (-1200 4525)(-1200 4475);
WIRE 16 -1 (-1200 4475)(-1400 4475);
WIRE 16 -1 (-1200 4575)(-1200 4525);
WIRE 16 -1 (-1200 4525)(-1400 4525);
WIRE 16 -1 (-1200 4625)(-1200 4575);
WIRE 16 -1 (-1200 4575)(-1400 4575);
WIRE 16 -1 (-1200 4675)(-1200 4625);
WIRE 16 -1 (-1200 4625)(-1400 4625);
WIRE 16 -1 (-1200 4725)(-1200 4675);
WIRE 16 -1 (-1200 4675)(-1400 4675);
WIRE 16 -1 (-1200 4775)(-1200 4725);
WIRE 16 -1 (-1200 4725)(-1400 4725);
WIRE 16 -1 (-1200 4825)(-1200 4775);
WIRE 16 -1 (-1200 4775)(-1400 4775);
WIRE 16 -1 (-1200 4875)(-1200 4825);
WIRE 16 -1 (-1200 4825)(-1400 4825);
WIRE 16 -1 (-1200 4925)(-1200 4875);
WIRE 16 -1 (-1200 4875)(-1400 4875);
WIRE 16 -1 (-1200 4975)(-1200 4925);
WIRE 16 -1 (-1200 4925)(-1400 4925);
WIRE 16 -1 (-1200 5025)(-1200 4975);
WIRE 16 -1 (-1200 4975)(-1400 4975);
WIRE 16 -1 (-1200 5075)(-1200 5025);
WIRE 16 -1 (-1200 5025)(-1400 5025);
WIRE 16 -1 (-1200 5125)(-1200 5075);
WIRE 16 -1 (-1200 5075)(-1400 5075);
WIRE 16 -1 (-1200 5175)(-1200 5125);
WIRE 16 -1 (-1200 5125)(-1400 5125);
WIRE 16 -1 (-1200 5225)(-1200 5175);
WIRE 16 -1 (-1200 5175)(-1400 5175);
WIRE 16 -1 (-1200 5275)(-1200 5225);
WIRE 16 -1 (-1200 5225)(-1400 5225);
WIRE 16 -1 (-1200 5325)(-1200 5275);
WIRE 16 -1 (-1200 5275)(-1400 5275);
WIRE 16 -1 (-1200 5375)(-1200 5325);
WIRE 16 -1 (-1200 5325)(-1400 5325);
WIRE 16 -1 (-1200 5425)(-1200 5375);
WIRE 16 -1 (-1200 5375)(-1400 5375);
WIRE 16 -1 (-1200 5475)(-1200 5425);
WIRE 16 -1 (-1200 5425)(-1400 5425);
WIRE 16 -1 (-1200 5525)(-1200 5475);
WIRE 16 -1 (-1200 5475)(-1400 5475);
WIRE 16 -1 (-1200 5575)(-1200 5525);
WIRE 16 -1 (-1200 5525)(-1400 5525);
WIRE 16 -1 (-1200 5625)(-1200 5575);
WIRE 16 -1 (-1200 5575)(-1400 5575);
WIRE 16 -1 (-1200 5675)(-1200 5625);
WIRE 16 -1 (-1200 5625)(-1400 5625);
WIRE 16 -1 (-1200 5725)(-1200 5675);
WIRE 16 -1 (-1200 5675)(-1400 5675);
WIRE 16 -1 (-1200 5775)(-1200 5725);
WIRE 16 -1 (-1200 5725)(-1400 5725);
WIRE 16 -1 (-1200 5825)(-1200 5775);
WIRE 16 -1 (-1200 5775)(-1400 5775);
WIRE 16 -1 (-1200 5875)(-1200 5825);
WIRE 16 -1 (-1200 5825)(-1400 5825);
WIRE 16 -1 (-1200 5875)(-1400 5875);
WIRE 16 -1 (-5150 4900)(-5150 4850);
WIRE 16 -1 (-5150 4950)(-5150 4900);
WIRE 16 -1 (-5375 4900)(-5150 4900);
WIRE 16 -1 (-5150 4850)(-5150 4800);
WIRE 16 -1 (-5375 4850)(-5150 4850);
WIRE 16 -1 (-5150 4800)(-5375 4800);
WIRE 16 -1 (-5150 5000)(-5150 4950);
WIRE 16 -1 (-5375 4950)(-5150 4950);
WIRE 16 -1 (-5150 5050)(-5150 5000);
WIRE 16 -1 (-5375 5000)(-5150 5000);
WIRE 16 -1 (-5150 5050)(-4100 5050);
WIRE 16 -1 (-5375 5050)(-5150 5050);
WIRE 16 -1 (-4100 5050)(-4100 4550);
WIRE 16 -1 (-4100 5050)(-4100 5275);
WIRE 16 -1 (-5125 4550)(-4100 4550);
WIRE 16 -1 (-5125 4550)(-5125 4500);
WIRE 16 -1 (-5125 4550)(-5375 4550);
WIRE 16 -1 (-5125 4500)(-5125 4450);
WIRE 16 -1 (-5375 4500)(-5125 4500);
WIRE 16 -1 (-5125 4450)(-5125 4400);
WIRE 16 -1 (-5375 4450)(-5125 4450);
WIRE 16 -1 (-5375 4400)(-5125 4400);
WIRE 16 -1 (-5125 4400)(-5125 4350);
WIRE 16 -1 (-5125 4350)(-5125 4300);
WIRE 16 -1 (-5375 4350)(-5125 4350);
WIRE 16 -1 (-5125 4300)(-5125 4250);
WIRE 16 -1 (-5375 4300)(-5125 4300);
WIRE 16 -1 (-5125 4250)(-5125 4200);
WIRE 16 -1 (-5375 4250)(-5125 4250);
WIRE 16 -1 (-5125 4200)(-5125 4150);
WIRE 16 -1 (-5375 4200)(-5125 4200);
WIRE 16 -1 (-5125 4150)(-5125 4100);
WIRE 16 -1 (-5375 4150)(-5125 4150);
WIRE 16 -1 (-5125 4100)(-5375 4100);
WIRE 16 -1 (-5050 3950)(-4075 3950);
WIRE 16 -1 (-5050 3950)(-5050 3900);
WIRE 16 -1 (-5375 3950)(-5050 3950);
WIRE 16 -1 (-4075 4050)(-4075 3950);
WIRE 16 -1 (-5050 3900)(-5050 3850);
WIRE 16 -1 (-5375 3900)(-5050 3900);
WIRE 16 -1 (-5050 3850)(-5050 3800);
WIRE 16 -1 (-5375 3850)(-5050 3850);
WIRE 16 -1 (-5050 3800)(-5375 3800);
WIRE 16 -1 (-5125 4700)(-5125 4650);
WIRE 16 -1 (-5125 4750)(-5125 4700);
WIRE 16 -1 (-5375 4700)(-5125 4700);
WIRE 16 -1 (-5125 4650)(-5375 4650);
WIRE 16 -1 (-5125 4650)(-5125 4600);
WIRE 16 -1 (-5125 4600)(-5375 4600);
WIRE 16 -1 (-5125 4750)(-4675 4750);
WIRE 16 -1 (-5375 4750)(-5125 4750);
WIRE 16 -1 (-4675 4750)(-4675 4800);
WIRE 16 -1 (-875 2325)(-875 2275);
WIRE 16 -1 (-875 2325)(-1400 2325);
FORCEPROP 2 LAST SIG_NAME NCF_CPU1_P0_GND
J 0
(-1285 2335);
DISPLAY 0.553191 (-1285 2335);
FORCEPROP 2 LASTPROP $XRERR UNIQUE?
J 0
(-1525 2335);
DISPLAY 0.638298 (-1525 2335);
PAINT MONO (-1525 2335);
DISPLAY INVISIBLE (-1525 2335);
WIRE 16 -1 (-875 2275)(-875 2225);
WIRE 16 -1 (-875 2275)(-1400 2275);
WIRE 16 -1 (-875 2225)(-875 2175);
WIRE 16 -1 (-875 2225)(-1400 2225);
WIRE 16 -1 (-875 2175)(-875 2125);
WIRE 16 -1 (-875 2175)(-1400 2175);
WIRE 16 -1 (-875 2125)(-875 2075);
WIRE 16 -1 (-875 2125)(-1400 2125);
WIRE 16 -1 (-875 2075)(-1400 2075);
WIRE 16 -1 (-875 2075)(-875 2025);
WIRE 16 -1 (-875 2025)(-875 1975);
WIRE 16 -1 (-875 2025)(-1400 2025);
WIRE 16 -1 (-875 1975)(-875 1925);
WIRE 16 -1 (-875 1975)(-1400 1975);
WIRE 16 -1 (-875 1925)(-875 1875);
WIRE 16 -1 (-875 1925)(-1400 1925);
WIRE 16 -1 (-875 1875)(-875 1825);
WIRE 16 -1 (-875 1875)(-1400 1875);
WIRE 16 -1 (-875 1825)(-875 1650);
WIRE 16 -1 (-875 1825)(-1400 1825);
WIRE 16 -1 (-1400 2375)(-725 2375);
FORCEPROP 2 LAST SIG_NAME NCF_A1_CPU1_P0_GND
J 0
(-1235 2385);
DISPLAY 0.553191 (-1235 2385);
FORCEPROP 2 LASTPROP $XRERR UNIQUE?
J 0
(-1475 2385);
DISPLAY 0.638298 (-1475 2385);
PAINT MONO (-1475 2385);
DISPLAY INVISIBLE (-1475 2385);
WIRE 16 -1 (-725 2375)(-725 2200);
WIRE 16 -1 (-6525 4400)(-7775 4400);
WIRE 16 -1 (-7775 4650)(-7775 4400);
WIRE 16 -1 (-6950 4850)(-6525 4850);
WIRE 16 -1 (-6950 4900)(-6950 4850);
WIRE 16 -1 (-6525 4900)(-6950 4900);
WIRE 16 -1 (-6950 4950)(-6950 4900);
WIRE 16 -1 (-6525 4950)(-6950 4950);
WIRE 16 -1 (-6950 5000)(-6950 4950);
WIRE 16 -1 (-6525 5000)(-6950 5000);
WIRE 16 -1 (-6950 5050)(-6950 5000);
WIRE 16 -1 (-6525 5050)(-6950 5050);
WIRE 16 -1 (-6950 5050)(-7200 5050);
WIRE 16 -1 (-7200 5050)(-7200 5100);
DOT 1 (-5050 3850);
DOT 1 (-5050 3950);
DOT 1 (-5050 3900);
DOT 1 (-6950 4900);
DOT 1 (-6950 4950);
DOT 1 (-6950 5000);
DOT 1 (-6950 5050);
DOT 1 (-5125 4150);
DOT 1 (-5125 4200);
DOT 1 (-5125 4300);
DOT 1 (-5125 4250);
DOT 1 (-5125 4350);
DOT 1 (-5125 4400);
DOT 1 (-5125 4450);
DOT 1 (-5125 4500);
DOT 1 (-5125 4550);
DOT 1 (-5125 4650);
DOT 1 (-5125 4700);
DOT 1 (-5150 4850);
DOT 1 (-5125 4750);
DOT 1 (-5150 4950);
DOT 1 (-5150 4900);
DOT 1 (-5150 5000);
DOT 1 (-5150 5050);
DOT 1 (-4100 5050);
DOT 1 (-2550 1975);
DOT 1 (-2550 2025);
DOT 1 (-2550 1925);
DOT 1 (-2550 1825);
DOT 1 (-2550 1875);
DOT 1 (-2550 3025);
DOT 1 (-2550 2775);
DOT 1 (-2550 2975);
DOT 1 (-2550 2925);
DOT 1 (-2550 2875);
DOT 1 (-2550 2825);
DOT 1 (-2550 2725);
DOT 1 (-2550 2675);
DOT 1 (-2550 2625);
DOT 1 (-2550 2575);
DOT 1 (-2550 2525);
DOT 1 (-2550 2475);
DOT 1 (-2550 2225);
DOT 1 (-2550 2425);
DOT 1 (-2550 2375);
DOT 1 (-2550 2325);
DOT 1 (-2550 2275);
DOT 1 (-2550 2175);
DOT 1 (-2550 2125);
DOT 1 (-2550 2075);
DOT 1 (-2550 3075);
DOT 1 (-2550 4075);
DOT 1 (-2550 4025);
DOT 1 (-2550 3925);
DOT 1 (-2550 3975);
DOT 1 (-2550 3875);
DOT 1 (-2550 3825);
DOT 1 (-2550 3775);
DOT 1 (-2550 3625);
DOT 1 (-2550 3725);
DOT 1 (-2550 3575);
DOT 1 (-2550 3525);
DOT 1 (-2550 3675);
DOT 1 (-2550 3275);
DOT 1 (-2550 3475);
DOT 1 (-2550 3425);
DOT 1 (-2550 3325);
DOT 1 (-2550 3375);
DOT 1 (-2550 3175);
DOT 1 (-2550 3225);
DOT 1 (-2550 3125);
DOT 1 (-875 1825);
DOT 1 (-875 1875);
DOT 1 (-875 1925);
DOT 1 (-875 1975);
DOT 1 (-875 2025);
DOT 1 (-1200 2475);
DOT 1 (-1200 2525);
DOT 1 (-1200 2575);
DOT 1 (-1200 2625);
DOT 1 (-1200 2675);
DOT 1 (-1200 2775);
DOT 1 (-1200 2725);
DOT 1 (-1200 2825);
DOT 1 (-1200 2875);
DOT 1 (-1200 2925);
DOT 1 (-1200 3025);
DOT 1 (-1200 2975);
DOT 1 (-1200 3075);
DOT 1 (-1200 3125);
DOT 1 (-1200 3175);
DOT 1 (-1200 3225);
DOT 1 (-1200 3275);
DOT 1 (-1200 3325);
DOT 1 (-1200 3425);
DOT 1 (-1200 3375);
DOT 1 (-1200 3475);
DOT 1 (-1200 3525);
DOT 1 (-1200 3575);
DOT 1 (-1200 3675);
DOT 1 (-1200 3625);
DOT 1 (-1200 3725);
DOT 1 (-1200 3775);
DOT 1 (-1200 3825);
DOT 1 (-1200 3925);
DOT 1 (-1200 3875);
DOT 1 (-1200 3975);
DOT 1 (-1200 4025);
DOT 1 (-1200 4075);
DOT 1 (-875 2075);
DOT 1 (-875 2125);
DOT 1 (-875 2175);
DOT 1 (-875 2225);
DOT 1 (-875 2275);
DOT 1 (-2550 4325);
DOT 1 (-2550 4275);
DOT 1 (-2550 5075);
DOT 1 (-2550 4825);
DOT 1 (-2550 5025);
DOT 1 (-2550 4975);
DOT 1 (-2550 4925);
DOT 1 (-2550 4875);
DOT 1 (-2550 4775);
DOT 1 (-2550 4725);
DOT 1 (-2550 4675);
DOT 1 (-2550 4625);
DOT 1 (-2550 4575);
DOT 1 (-2550 4525);
DOT 1 (-2550 4475);
DOT 1 (-2550 4425);
DOT 1 (-2550 4375);
DOT 1 (-2550 4225);
DOT 1 (-2550 4175);
DOT 1 (-2550 4125);
DOT 1 (-2550 5125);
DOT 1 (-2550 5475);
DOT 1 (-2550 5525);
DOT 1 (-2550 5825);
DOT 1 (-2550 5775);
DOT 1 (-2550 5575);
DOT 1 (-2550 5725);
DOT 1 (-2550 5675);
DOT 1 (-2550 5625);
DOT 1 (-2550 5325);
DOT 1 (-2550 5425);
DOT 1 (-2550 5375);
DOT 1 (-2550 5275);
DOT 1 (-2550 5225);
DOT 1 (-2550 5175);
DOT 1 (-1200 4175);
DOT 1 (-1200 4125);
DOT 1 (-1200 4225);
DOT 1 (-1200 4275);
DOT 1 (-1200 4325);
DOT 1 (-1200 4375);
DOT 1 (-1200 4425);
DOT 1 (-1200 4475);
DOT 1 (-1200 4525);
DOT 1 (-1200 4575);
DOT 1 (-1200 4625);
DOT 1 (-1200 4675);
DOT 1 (-1200 4725);
DOT 1 (-1200 4825);
DOT 1 (-1200 4775);
DOT 1 (-1200 4875);
DOT 1 (-1200 4925);
DOT 1 (-1200 4975);
DOT 1 (-1200 5025);
DOT 1 (-1200 5075);
DOT 1 (-1200 5125);
DOT 1 (-1200 5175);
DOT 1 (-1200 5225);
DOT 1 (-1200 5275);
DOT 1 (-1200 5325);
DOT 1 (-1200 5375);
DOT 1 (-1200 5425);
DOT 1 (-1200 5475);
DOT 1 (-1200 5525);
DOT 1 (-1200 5575);
DOT 1 (-1200 5625);
DOT 1 (-1200 5675);
DOT 1 (-1200 5725);
DOT 1 (-1200 5775);
DOT 1 (-1200 5825);
DOT 1 (-7075 3950);
QUIT
